# T6G (Grand Teton) — schematic netlist excerpt (pin names and nets, part order shuffled) for the footprints in the layout excerpt that follows; sources: Cadence DE-HDL packaged netlist, KiCad conversion of 04192023_DAF0TMB3IC0_F0TG_MB_C_brd_V02_OCP.brd

R8040  Q_RES  10K 1% CHIP  pkg 0402LF  page 104 : A = P3V3_AUX ; B = PWRGD_CHGL_CPU1
PC6552  Q_CAP  2.2UF 10V 10% X6S  pkg C0402  page 363 : A = P0V9_RETIMER_CPU0_VCC1 ; B = GND

(kicad_pcb
	(version 20260206)
	(generator "pcbnew")
	(generator_version "10.0")
	(general
		(thickness 1.6)
		(legacy_teardrops no)
	)
	(paper "A4")
	(title_block
		(title "04192023_DAF0TMB3IC0_F0TG_MB_C_brd_V02_OCP.brd")
		(comment 1 "Grand Teton / footprints 4521-4522 of 8354")
	)
	(layers
		(0 "F.Cu" signal "TOP")
		(4 "In1.Cu" signal "GND")
		(6 "In2.Cu" signal "IN1")
		(8 "In3.Cu" signal "GND1")
		(10 "In4.Cu" signal "IN2")
		(12 "In5.Cu" signal "GND2")
		(14 "In6.Cu" signal "IN3")
		(16 "In7.Cu" signal "GND3")
		(18 "In8.Cu" signal "VCC")
		(20 "In9.Cu" signal "VCC1")
		(22 "In10.Cu" signal "GND4")
		(24 "In11.Cu" signal "IN4")
		(26 "In12.Cu" signal "GND5")
		(28 "In13.Cu" signal "IN5")
		(30 "In14.Cu" signal "GND6")
		(32 "In15.Cu" signal "IN6")
		(34 "In16.Cu" signal "GND7")
		(2 "B.Cu" signal "BOTTOM")
		(9 "F.Adhes" user "F.Adhesive")
		(11 "B.Adhes" user "B.Adhesive")
		(13 "F.Paste" user "Package Geometry/Pastemask Top")
		(15 "B.Paste" user "Package Geometry/Pastemask Bottom")
		(5 "F.SilkS" user "Ref Des/Silkscreen Top")
		(7 "B.SilkS" user "Ref Des/Silkscreen Bottom")
		(1 "F.Mask" user "Board Geometry/Soldermask Top")
		(3 "B.Mask" user "Board Geometry/Soldermask Bottom")
		(17 "Dwgs.User" user "User.Drawings")
		(19 "Cmts.User" user "User.Comments")
		(21 "Eco1.User" user "User.Eco1")
		(23 "Eco2.User" user "User.Eco2")
		(25 "Edge.Cuts" user "Board Geometry/Outline")
		(27 "Margin" user)
		(31 "F.CrtYd" user "Package Geometry/Place Bound Top")
		(29 "B.CrtYd" user "Package Geometry/Place Bound Bottom")
		(35 "F.Fab" user "Ref Des/Assembly Top")
		(33 "B.Fab" user "Ref Des/Assembly Bottom")
	)
	(footprint ""
		(layer "F.Cu")
		(at 441.430156 -399.213578 90)
		(property "Reference" "PC6552"
			(at 0 0 90)
			(layer "F.SilkS")
			(hide yes)
			(effects
				(font
					(size 1.27 1.27)
				)
			)
		)
		(property "Value" ""
			(at 0 0 90)
			(layer "F.Fab")
			(effects
				(font
					(size 1.27 1.27)
				)
			)
		)
		(duplicate_pad_numbers_are_jumpers no)
		(fp_line
			(start 0.7874 -0.4064)
			(end 0.7874 -0.105156)
			(stroke
				(width 0.1524)
				(type default)
			)
			(layer "F.SilkS")
		)
		(fp_line
			(start -0.7874 -0.4064)
			(end 0.7874 -0.4064)
			(stroke
				(width 0.1524)
				(type default)
			)
			(layer "F.SilkS")
		)
		(fp_line
			(start 0.582422 0.4064)
			(end -0.7874 0.4064)
			(stroke
				(width 0.1524)
				(type default)
			)
			(layer "F.SilkS")
		)
		(fp_line
			(start -0.7874 0.4064)
			(end -0.7874 -0.4064)
			(stroke
				(width 0.1524)
				(type default)
			)
			(layer "F.SilkS")
		)
		(fp_line
			(start -0.12065 -0.305054)
			(end -0.12065 -0.2794)
			(stroke
				(width 0.1)
				(type default)
			)
			(layer "F.Fab")
		)
		(fp_line
			(start -0.67945 -0.305054)
			(end -0.12065 -0.305054)
			(stroke
				(width 0.1)
				(type default)
			)
			(layer "F.Fab")
		)
		(fp_line
			(start 0.67945 -0.3048)
			(end 0.67945 0.3048)
			(stroke
				(width 0.1)
				(type default)
			)
			(layer "F.Fab")
		)
		(fp_line
			(start 0.12065 -0.3048)
			(end 0.67945 -0.3048)
			(stroke
				(width 0.1)
				(type default)
			)
			(layer "F.Fab")
		)
		(fp_line
			(start 0.12065 -0.2794)
			(end 0.12065 -0.3048)
			(stroke
				(width 0.1)
				(type default)
			)
			(layer "F.Fab")
		)
		(fp_line
			(start -0.12065 -0.2794)
			(end 0.12065 -0.2794)
			(stroke
				(width 0.1)
				(type default)
			)
			(layer "F.Fab")
		)
		(fp_line
			(start 0.120396 0.2794)
			(end -0.12065 0.2794)
			(stroke
				(width 0.1)
				(type default)
			)
			(layer "F.Fab")
		)
		(fp_line
			(start -0.12065 0.2794)
			(end -0.12065 0.3048)
			(stroke
				(width 0.1)
				(type default)
			)
			(layer "F.Fab")
		)
		(fp_line
			(start 0.67945 0.3048)
			(end 0.120396 0.3048)
			(stroke
				(width 0.1)
				(type default)
			)
			(layer "F.Fab")
		)
		(fp_line
			(start 0.120396 0.3048)
			(end 0.120396 0.2794)
			(stroke
				(width 0.1)
				(type default)
			)
			(layer "F.Fab")
		)
		(fp_line
			(start -0.12065 0.3048)
			(end -0.67945 0.3048)
			(stroke
				(width 0.1)
				(type default)
			)
			(layer "F.Fab")
		)
		(fp_line
			(start -0.67945 0.3048)
			(end -0.67945 -0.305054)
			(stroke
				(width 0.1)
				(type default)
			)
			(layer "F.Fab")
		)
		(pad "1" smd circle
			(at -0.40005 0 90)
			(size 0 0)
			(layers "F.Cu" "F.Mask" "F.Paste")
			(net "P0V9_RETIMER_CPU0_VCC1")
		)
		(pad "2" smd circle
			(at 0.40005 0 90)
			(size 0 0)
			(layers "F.Cu" "F.Mask" "F.Paste")
			(net "GND")
		)
	)
	(footprint ""
		(layer "F.Cu")
		(at 196.469 -92.456)
		(property "Reference" "R8040"
			(at 0 0 0)
			(layer "F.SilkS")
			(hide yes)
			(effects
				(font
					(size 1.27 1.27)
				)
			)
		)
		(property "Value" ""
			(at 0 0 0)
			(layer "F.Fab")
			(effects
				(font
					(size 1.27 1.27)
				)
			)
		)
		(duplicate_pad_numbers_are_jumpers no)
		(fp_line
			(start -0.7874 -0.4064)
			(end 0.7874 -0.4064)
			(stroke
				(width 0.1524)
				(type default)
			)
			(layer "F.SilkS")
		)
		(fp_line
			(start -0.7874 0.4064)
			(end -0.7874 -0.4064)
			(stroke
				(width 0.1524)
				(type default)
			)
			(layer "F.SilkS")
		)
		(fp_line
			(start 0.7874 -0.4064)
			(end 0.7874 0.4064)
			(stroke
				(width 0.1524)
				(type default)
			)
			(layer "F.SilkS")
		)
		(fp_line
			(start 0.7874 0.4064)
			(end -0.7874 0.4064)
			(stroke
				(width 0.1524)
				(type default)
			)
			(layer "F.SilkS")
		)
		(fp_line
			(start -0.67945 -0.305054)
			(end -0.12065 -0.305054)
			(stroke
				(width 0.1)
				(type default)
			)
			(layer "F.Fab")
		)
		(fp_line
			(start -0.67945 0.3048)
			(end -0.67945 -0.305054)
			(stroke
				(width 0.1)
				(type default)
			)
			(layer "F.Fab")
		)
		(fp_line
			(start -0.12065 -0.305054)
			(end -0.12065 -0.2794)
			(stroke
				(width 0.1)
				(type default)
			)
			(layer "F.Fab")
		)
		(fp_line
			(start -0.12065 -0.2794)
			(end 0.12065 -0.2794)
			(stroke
				(width 0.1)
				(type default)
			)
			(layer "F.Fab")
		)
		(fp_line
			(start -0.12065 0.2794)
			(end -0.12065 0.3048)
			(stroke
				(width 0.1)
				(type default)
			)
			(layer "F.Fab")
		)
		(fp_line
			(start -0.12065 0.3048)
			(end -0.67945 0.3048)
			(stroke
				(width 0.1)
				(type default)
			)
			(layer "F.Fab")
		)
		(fp_line
			(start 0.120396 0.2794)
			(end -0.12065 0.2794)
			(stroke
				(width 0.1)
				(type default)
			)
			(layer "F.Fab")
		)
		(fp_line
			(start 0.120396 0.3048)
			(end 0.120396 0.2794)
			(stroke
				(width 0.1)
				(type default)
			)
			(layer "F.Fab")
		)
		(fp_line
			(start 0.12065 -0.3048)
			(end 0.67945 -0.3048)
			(stroke
				(width 0.1)
				(type default)
			)
			(layer "F.Fab")
		)
		(fp_line
			(start 0.12065 -0.2794)
			(end 0.12065 -0.3048)
			(stroke
				(width 0.1)
				(type default)
			)
			(layer "F.Fab")
		)
		(fp_line
			(start 0.67945 -0.3048)
			(end 0.67945 0.3048)
			(stroke
				(width 0.1)
				(type default)
			)
			(layer "F.Fab")
		)
		(fp_line
			(start 0.67945 0.3048)
			(end 0.120396 0.3048)
			(stroke
				(width 0.1)
				(type default)
			)
			(layer "F.Fab")
		)
		(pad "1" smd circle
			(at -0.40005 0)
			(size 0 0)
			(layers "F.Cu" "F.Mask" "F.Paste")
			(net "P3V3_AUX")
		)
		(pad "2" smd circle
			(at 0.40005 0)
			(size 0 0)
			(layers "F.Cu" "F.Mask" "F.Paste")
			(net "PWRGD_CHGL_CPU1")
		)
	)
)
